# S9S_MB_2U (Grand Teton) — schematic netlist excerpt (pin names and nets, part order shuffled) for the footprints in the layout excerpt that follows; sources: Cadence DE-HDL packaged netlist, KiCad conversion of 03242023_DA0F0TMBIJ0_F0T_Motherboard_J_brd_V01_OCP.brd

R2583  Q_RES  10K 1% CHIP  pkg 0402LF  page 299 : A = P3V3_AUX ; B = PWRGD_PVPP_HBM_CPU1_R

PU205  MP5016GQHLZ  MP5016GQH-L-Z EMPTY  pkg QFN8_2X1-5  page 157
  VCC  = P3V3_AUX
  GND  = GND
  ILIMIT  = P3V3_OCP_ILIMIT_1
  MODE  = P3V3_OCP_MODE_1
  SOURCE  = P3V3_OCP_SFF_R
  GATE  = P3V3_OCP_GATE_1
  EN  = P3V3_OCP_EN_1_R2
  DV_DT  = P3V3_OCP_DVDT_1

(kicad_pcb
	(version 20260206)
	(generator "pcbnew")
	(generator_version "10.0")
	(general
		(thickness 1.6)
		(legacy_teardrops no)
	)
	(paper "A4")
	(title_block
		(title "03242023_DA0F0TMBIJ0_F0T_Motherboard_J_brd_V01_OCP.brd")
		(comment 1 "Grand Teton / footprints 3752-3753 of 6105")
	)
	(layers
		(0 "F.Cu" signal "TOP")
		(4 "In1.Cu" signal "GND")
		(6 "In2.Cu" signal "IN1")
		(8 "In3.Cu" signal "GND1")
		(10 "In4.Cu" signal "IN2")
		(12 "In5.Cu" signal "GND2")
		(14 "In6.Cu" signal "IN3")
		(16 "In7.Cu" signal "GND3")
		(18 "In8.Cu" signal "VCC")
		(20 "In9.Cu" signal "VCC1")
		(22 "In10.Cu" signal "GND4")
		(24 "In11.Cu" signal "IN4")
		(26 "In12.Cu" signal "GND5")
		(28 "In13.Cu" signal "IN5")
		(30 "In14.Cu" signal "GND6")
		(32 "In15.Cu" signal "IN6")
		(34 "In16.Cu" signal "GND7")
		(2 "B.Cu" signal "BOTTOM")
		(9 "F.Adhes" user "F.Adhesive")
		(11 "B.Adhes" user "B.Adhesive")
		(13 "F.Paste" user "Package Geometry/Pastemask Top")
		(15 "B.Paste" user "Package Geometry/Pastemask Bottom")
		(5 "F.SilkS" user "Ref Des/Silkscreen Top")
		(7 "B.SilkS" user "Ref Des/Silkscreen Bottom")
		(1 "F.Mask" user "Board Geometry/Soldermask Top")
		(3 "B.Mask" user "Board Geometry/Soldermask Bottom")
		(17 "Dwgs.User" user "User.Drawings")
		(19 "Cmts.User" user "User.Comments")
		(21 "Eco1.User" user "User.Eco1")
		(23 "Eco2.User" user "User.Eco2")
		(25 "Edge.Cuts" user "Board Geometry/Outline")
		(27 "Margin" user)
		(31 "F.CrtYd" user "Package Geometry/Place Bound Top")
		(29 "B.CrtYd" user "Package Geometry/Place Bound Bottom")
		(35 "F.Fab" user "Ref Des/Assembly Top")
		(33 "B.Fab" user "Ref Des/Assembly Bottom")
	)
	(footprint ""
		(layer "F.Cu")
		(at 420.52494 -105.207308)
		(property "Reference" "PU205"
			(at -5.1562 -1.20523 0)
			(unlocked yes)
			(layer "F.SilkS")
			(effects
				(font
					(size 0.7874 0.5842)
					(thickness 0.1524)
				)
			)
		)
		(property "Value" ""
			(at 0 0 0)
			(layer "F.Fab")
			(effects
				(font
					(size 1.27 1.27)
				)
			)
		)
		(duplicate_pad_numbers_are_jumpers no)
		(fp_line
			(start -1.239774 -1.495298)
			(end 1.239774 -1.495298)
			(stroke
				(width 0.1524)
				(type default)
			)
			(layer "F.SilkS")
		)
		(fp_line
			(start -1.239774 1.495298)
			(end -1.239774 -1.495298)
			(stroke
				(width 0.1524)
				(type default)
			)
			(layer "F.SilkS")
		)
		(fp_line
			(start 1.239774 -1.495298)
			(end 1.239774 1.495298)
			(stroke
				(width 0.1524)
				(type default)
			)
			(layer "F.SilkS")
		)
		(fp_line
			(start 1.239774 1.495298)
			(end -1.239774 1.495298)
			(stroke
				(width 0.1524)
				(type default)
			)
			(layer "F.SilkS")
		)
		(fp_poly
			(pts
				(xy -1.887474 -1.720596) (xy -1.528318 -0.643128) (xy -2.60604 -1.002284)
			)
			(stroke
				(width 0)
				(type default)
			)
			(fill yes)
			(layer "F.SilkS")
		)
		(fp_line
			(start -0.8001 -1.050036)
			(end 0.8001 -1.050036)
			(stroke
				(width 0.1)
				(type default)
			)
			(layer "F.Fab")
		)
		(fp_line
			(start -0.8001 1.050036)
			(end -0.8001 -1.050036)
			(stroke
				(width 0.1)
				(type default)
			)
			(layer "F.Fab")
		)
		(fp_line
			(start 0.8001 -1.050036)
			(end 0.8001 1.050036)
			(stroke
				(width 0.1)
				(type default)
			)
			(layer "F.Fab")
		)
		(fp_line
			(start 0.8001 1.050036)
			(end -0.8001 1.050036)
			(stroke
				(width 0.1)
				(type default)
			)
			(layer "F.Fab")
		)
		(fp_poly
			(pts
				(xy -2.458974 -0.508) (xy -2.458974 0.508) (xy -1.442974 0)
			)
			(stroke
				(width 0)
				(type default)
			)
			(fill yes)
			(layer "F.Fab")
		)
		(pad "1_2" smd circle
			(at -0.374904 0 90)
			(size 0 0)
			(layers "F.Cu" "F.Mask" "F.Paste")
			(net "P3V3_AUX")
		)
		(pad "3" smd rect
			(at -0.499872 0.999998)
			(size 0.254 0.7112)
			(layers "F.Cu" "F.Mask" "F.Paste")
			(net "GND")
		)
		(pad "4" smd rect
			(at 0 0.999998)
			(size 0.254 0.7112)
			(layers "F.Cu" "F.Mask" "F.Paste")
			(net "P3V3_OCP_ILIMIT_1")
		)
		(pad "5" smd rect
			(at 0.499872 0.999998)
			(size 0.254 0.7112)
			(layers "F.Cu" "F.Mask" "F.Paste")
			(net "P3V3_OCP_MODE_1")
		)
		(pad "6_7" smd circle
			(at 0.374904 0 270)
			(size 0 0)
			(layers "F.Cu" "F.Mask" "F.Paste")
			(net "P3V3_OCP_SFF_R")
		)
		(pad "8" smd rect
			(at 0.499872 -0.999998)
			(size 0.254 0.7112)
			(layers "F.Cu" "F.Mask" "F.Paste")
			(net "P3V3_OCP_GATE_1")
		)
		(pad "9" smd rect
			(at 0 -0.999998)
			(size 0.254 0.7112)
			(layers "F.Cu" "F.Mask" "F.Paste")
			(net "P3V3_OCP_EN_1_R2")
		)
		(pad "10" smd rect
			(at -0.499872 -0.999998)
			(size 0.254 0.7112)
			(layers "F.Cu" "F.Mask" "F.Paste")
			(net "P3V3_OCP_DVDT_1")
		)
	)
	(footprint ""
		(layer "F.Cu")
		(at 121.784364 -355.69779)
		(property "Reference" "R2583"
			(at 0 0 0)
			(layer "F.SilkS")
			(hide yes)
			(effects
				(font
					(size 1.27 1.27)
				)
			)
		)
		(property "Value" ""
			(at 0 0 0)
			(layer "F.Fab")
			(effects
				(font
					(size 1.27 1.27)
				)
			)
		)
		(duplicate_pad_numbers_are_jumpers no)
		(fp_line
			(start -0.7874 -0.4064)
			(end 0.7874 -0.4064)
			(stroke
				(width 0.1524)
				(type default)
			)
			(layer "F.SilkS")
		)
		(fp_line
			(start -0.7874 0.4064)
			(end -0.7874 -0.4064)
			(stroke
				(width 0.1524)
				(type default)
			)
			(layer "F.SilkS")
		)
		(fp_line
			(start 0.7874 -0.4064)
			(end 0.7874 0.4064)
			(stroke
				(width 0.1524)
				(type default)
			)
			(layer "F.SilkS")
		)
		(fp_line
			(start 0.7874 0.4064)
			(end -0.7874 0.4064)
			(stroke
				(width 0.1524)
				(type default)
			)
			(layer "F.SilkS")
		)
		(fp_line
			(start -0.67945 -0.305054)
			(end -0.12065 -0.305054)
			(stroke
				(width 0.1)
				(type default)
			)
			(layer "F.Fab")
		)
		(fp_line
			(start -0.67945 0.3048)
			(end -0.67945 -0.305054)
			(stroke
				(width 0.1)
				(type default)
			)
			(layer "F.Fab")
		)
		(fp_line
			(start -0.12065 -0.305054)
			(end -0.12065 -0.2794)
			(stroke
				(width 0.1)
				(type default)
			)
			(layer "F.Fab")
		)
		(fp_line
			(start -0.12065 -0.2794)
			(end 0.12065 -0.2794)
			(stroke
				(width 0.1)
				(type default)
			)
			(layer "F.Fab")
		)
		(fp_line
			(start -0.12065 0.2794)
			(end -0.12065 0.3048)
			(stroke
				(width 0.1)
				(type default)
			)
			(layer "F.Fab")
		)
		(fp_line
			(start -0.12065 0.3048)
			(end -0.67945 0.3048)
			(stroke
				(width 0.1)
				(type default)
			)
			(layer "F.Fab")
		)
		(fp_line
			(start 0.120396 0.2794)
			(end -0.12065 0.2794)
			(stroke
				(width 0.1)
				(type default)
			)
			(layer "F.Fab")
		)
		(fp_line
			(start 0.120396 0.3048)
			(end 0.120396 0.2794)
			(stroke
				(width 0.1)
				(type default)
			)
			(layer "F.Fab")
		)
		(fp_line
			(start 0.12065 -0.3048)
			(end 0.67945 -0.3048)
			(stroke
				(width 0.1)
				(type default)
			)
			(layer "F.Fab")
		)
		(fp_line
			(start 0.12065 -0.2794)
			(end 0.12065 -0.3048)
			(stroke
				(width 0.1)
				(type default)
			)
			(layer "F.Fab")
		)
		(fp_line
			(start 0.67945 -0.3048)
			(end 0.67945 0.3048)
			(stroke
				(width 0.1)
				(type default)
			)
			(layer "F.Fab")
		)
		(fp_line
			(start 0.67945 0.3048)
			(end 0.120396 0.3048)
			(stroke
				(width 0.1)
				(type default)
			)
			(layer "F.Fab")
		)
		(pad "1" smd circle
			(at -0.40005 0)
			(size 0 0)
			(layers "F.Cu" "F.Mask" "F.Paste")
			(net "P3V3_AUX")
		)
		(pad "2" smd circle
			(at 0.40005 0)
			(size 0 0)
			(layers "F.Cu" "F.Mask" "F.Paste")
			(net "PWRGD_PVPP_HBM_CPU1_R")
		)
	)
)
